# BASEBOARD_FAB2 (Tioga Pass) — schematic netlist excerpt (pin names and nets, part order shuffled) for the footprints in the layout excerpt that follows; sources: Cadence DE-HDL packaged netlist, KiCad conversion of Wiwynn_Tioga_Pass_MB.brd

C1W17  CAP  10UF 16V 10% EMPTY  pkg 0805  page 101 : A = P3V3_STBY_MNG_RMII ; B = GND
C1M11  CAP  0.22UF 16V 10% X7R  pkg 0402  page 106 : A = P3E_CPU0_PE3_OCP_TXN<13> ; B = P3E_OCP_CPU0_PE3_C_TXN<13>
C1T11  CAP_A  0.1UF 16V 10% X7R  pkg 0402V  page 158 : A = P3V3_STBY ; B = GND

(kicad_pcb
	(version 20260206)
	(generator "pcbnew")
	(generator_version "10.0")
	(general
		(thickness 1.6)
		(legacy_teardrops no)
	)
	(paper "A4")
	(title_block
		(title "Wiwynn_Tioga_Pass_MB.brd")
		(comment 1 "Tioga Pass / footprints 2458-2460 of 4770")
	)
	(layers
		(0 "F.Cu" signal "TOP")
		(4 "In1.Cu" signal "L2GND")
		(6 "In2.Cu" signal "L3")
		(8 "In3.Cu" signal "L4GND")
		(10 "In4.Cu" signal "L5")
		(12 "In5.Cu" signal "L6GND")
		(14 "In6.Cu" signal "L7VCC")
		(16 "In7.Cu" signal "L8VCC")
		(18 "In8.Cu" signal "L9GND")
		(20 "In9.Cu" signal "L10")
		(22 "In10.Cu" signal "L11GND")
		(24 "In11.Cu" signal "L12")
		(26 "In12.Cu" signal "L13GND")
		(2 "B.Cu" signal "BOTTOM")
		(9 "F.Adhes" user "F.Adhesive")
		(11 "B.Adhes" user "B.Adhesive")
		(13 "F.Paste" user "Package Geometry/Pastemask Top")
		(15 "B.Paste" user "Package Geometry/Pastemask Bottom")
		(5 "F.SilkS" user "Ref Des/Silkscreen Top")
		(7 "B.SilkS" user "Ref Des/Silkscreen Bottom")
		(1 "F.Mask" user "Board Geometry/Soldermask Top")
		(3 "B.Mask" user "Board Geometry/Soldermask Bottom")
		(17 "Dwgs.User" user "User.Drawings")
		(19 "Cmts.User" user "User.Comments")
		(21 "Eco1.User" user "User.Eco1")
		(23 "Eco2.User" user "User.Eco2")
		(25 "Edge.Cuts" user "Board Geometry/Outline")
		(27 "Margin" user)
		(31 "F.CrtYd" user "Package Geometry/Place Bound Top")
		(29 "B.CrtYd" user "Package Geometry/Place Bound Bottom")
		(35 "F.Fab" user "Ref Des/Assembly Top")
		(33 "B.Fab" user "Ref Des/Assembly Bottom")
	)
	(footprint ""
		(layer "B.Cu")
		(at 458.851 -116.49202)
		(property "Reference" "C1M11"
			(at 0 0 0)
			(layer "B.SilkS")
			(hide yes)
			(effects
				(font
					(size 1.27 1.27)
				)
				(justify mirror)
			)
		)
		(property "Value" ""
			(at 0 0 0)
			(layer "B.Fab")
			(effects
				(font
					(size 1.27 1.27)
				)
				(justify mirror)
			)
		)
		(duplicate_pad_numbers_are_jumpers no)
		(fp_rect
			(start -0.3048 0.9906)
			(end 0.3048 -0.1016)
			(stroke
				(width 0)
				(type default)
			)
			(fill no)
			(layer "B.CrtYd")
		)
		(fp_line
			(start -0.3048 -0.1016)
			(end 0.3048 -0.1016)
			(stroke
				(width 0.1)
				(type default)
			)
			(layer "B.Fab")
		)
		(fp_line
			(start -0.3048 0.9906)
			(end -0.3048 -0.1016)
			(stroke
				(width 0.1)
				(type default)
			)
			(layer "B.Fab")
		)
		(fp_line
			(start 0.3048 -0.1016)
			(end 0.3048 0.9906)
			(stroke
				(width 0.1)
				(type default)
			)
			(layer "B.Fab")
		)
		(fp_line
			(start 0.3048 0.9906)
			(end -0.3048 0.9906)
			(stroke
				(width 0.1)
				(type default)
			)
			(layer "B.Fab")
		)
		(pad "1" smd rect
			(at 0 0 180)
			(size 0.508 0.508)
			(layers "B.Cu" "B.Mask" "B.Paste")
			(net "P3E_CPU0_PE3_OCP_TXN<13>")
		)
		(pad "2" smd rect
			(at 0 0.889 180)
			(size 0.508 0.508)
			(layers "B.Cu" "B.Mask" "B.Paste")
			(net "P3E_OCP_CPU0_PE3_C_TXN<13>")
		)
		(zone
			(layer "B.Cu")
			(hatch none 0.5)
			(connect_pads
				(clearance 0)
			)
			(min_thickness 0.25)
			(keepout
				(tracks not_allowed)
				(vias allowed)
				(pads allowed)
				(copperpour not_allowed)
				(footprints allowed)
			)
			(placement
				(enabled no)
				(sheetname "")
			)
			(fill
				(thermal_gap 0.5)
				(thermal_bridge_width 0.5)
				(island_removal_mode 0)
			)
			(polygon
				(pts
					(xy 458.597 -115.85702) (xy 459.105 -115.85702) (xy 459.105 -116.23802) (xy 458.597 -116.23802)
				)
			)
		)
		(zone
			(layer "B.Cu")
			(hatch none 0.5)
			(connect_pads
				(clearance 0)
			)
			(min_thickness 0.25)
			(keepout
				(tracks allowed)
				(vias not_allowed)
				(pads allowed)
				(copperpour not_allowed)
				(footprints allowed)
			)
			(placement
				(enabled no)
				(sheetname "")
			)
			(fill
				(thermal_gap 0.5)
				(thermal_bridge_width 0.5)
				(island_removal_mode 0)
			)
			(polygon
				(pts
					(xy 458.597 -115.85702) (xy 459.105 -115.85702) (xy 459.105 -116.23802) (xy 458.597 -116.23802)
				)
			)
		)
	)
	(footprint ""
		(layer "B.Cu")
		(at 475.361 -34.29)
		(property "Reference" "C1W17"
			(at -1.47828 0.78994 90)
			(unlocked yes)
			(layer "B.SilkS")
			(effects
				(font
					(size 0.4064 0.254)
					(thickness 0.1524)
				)
				(justify mirror)
			)
		)
		(property "Value" ""
			(at 0 0 0)
			(layer "B.Fab")
			(effects
				(font
					(size 1.27 1.27)
				)
				(justify mirror)
			)
		)
		(duplicate_pad_numbers_are_jumpers no)
		(fp_poly
			(pts
				(xy 0.7239 -0.2159) (xy -0.7239 -0.2159) (xy -0.7239 1.9939) (xy 0.7239 1.9939)
			)
			(stroke
				(width 0)
				(type default)
			)
			(fill no)
			(layer "B.CrtYd")
		)
		(fp_line
			(start -0.7239 -0.2159)
			(end 0.7239 -0.2159)
			(stroke
				(width 0.1)
				(type default)
			)
			(layer "B.Fab")
		)
		(fp_line
			(start -0.7239 1.9939)
			(end -0.7239 -0.2159)
			(stroke
				(width 0.1)
				(type default)
			)
			(layer "B.Fab")
		)
		(fp_line
			(start 0.7239 -0.2159)
			(end 0.7239 1.9939)
			(stroke
				(width 0.1)
				(type default)
			)
			(layer "B.Fab")
		)
		(fp_line
			(start 0.7239 1.9939)
			(end -0.7239 1.9939)
			(stroke
				(width 0.1)
				(type default)
			)
			(layer "B.Fab")
		)
		(pad "1" smd rect
			(at 0 0 180)
			(size 1.27 1.016)
			(layers "B.Cu" "B.Mask" "B.Paste")
			(net "P3V3_STBY_MNG_RMII")
		)
		(pad "2" smd rect
			(at 0 1.778 180)
			(size 1.27 1.016)
			(layers "B.Cu" "B.Mask" "B.Paste")
			(net "GND")
		)
		(zone
			(layer "B.Cu")
			(hatch none 0.5)
			(connect_pads
				(clearance 0)
			)
			(min_thickness 0.25)
			(keepout
				(tracks not_allowed)
				(vias allowed)
				(pads allowed)
				(copperpour not_allowed)
				(footprints allowed)
			)
			(placement
				(enabled no)
				(sheetname "")
			)
			(fill
				(thermal_gap 0.5)
				(thermal_bridge_width 0.5)
				(island_removal_mode 0)
			)
			(polygon
				(pts
					(xy 475.996 -33.782) (xy 474.726 -33.782) (xy 474.726 -33.02) (xy 475.996 -33.02)
				)
			)
		)
	)
	(footprint ""
		(layer "B.Cu")
		(at 489.08589 -33.674812 180)
		(property "Reference" "C1T11"
			(at 0 0 0)
			(layer "B.SilkS")
			(hide yes)
			(effects
				(font
					(size 1.27 1.27)
				)
				(justify mirror)
			)
		)
		(property "Value" ""
			(at 0 0 0)
			(layer "B.Fab")
			(effects
				(font
					(size 1.27 1.27)
				)
				(justify mirror)
			)
		)
		(duplicate_pad_numbers_are_jumpers no)
		(fp_poly
			(pts
				(xy -0.3048 -0.1016) (xy -0.3048 0.9906) (xy 0.3048 0.9906) (xy 0.3048 -0.1016)
			)
			(stroke
				(width 0)
				(type default)
			)
			(fill no)
			(layer "B.CrtYd")
		)
		(fp_line
			(start 0.3048 0.9906)
			(end -0.3048 0.9906)
			(stroke
				(width 0.1)
				(type default)
			)
			(layer "B.Fab")
		)
		(fp_line
			(start 0.3048 -0.1016)
			(end 0.3048 0.9906)
			(stroke
				(width 0.1)
				(type default)
			)
			(layer "B.Fab")
		)
		(fp_line
			(start -0.3048 0.9906)
			(end -0.3048 -0.1016)
			(stroke
				(width 0.1)
				(type default)
			)
			(layer "B.Fab")
		)
		(fp_line
			(start -0.3048 -0.1016)
			(end 0.3048 -0.1016)
			(stroke
				(width 0.1)
				(type default)
			)
			(layer "B.Fab")
		)
		(pad "1" smd rect
			(at 0 0)
			(size 0.508 0.508)
			(layers "B.Cu" "B.Mask" "B.Paste")
			(net "P3V3_STBY")
		)
		(pad "2" smd rect
			(at 0 0.889)
			(size 0.508 0.508)
			(layers "B.Cu" "B.Mask" "B.Paste")
			(net "GND")
		)
		(zone
			(layer "B.Cu")
			(hatch none 0.5)
			(connect_pads
				(clearance 0)
			)
			(min_thickness 0.25)
			(keepout
				(tracks not_allowed)
				(vias allowed)
				(pads allowed)
				(copperpour not_allowed)
				(footprints allowed)
			)
			(placement
				(enabled no)
				(sheetname "")
			)
			(fill
				(thermal_gap 0.5)
				(thermal_bridge_width 0.5)
				(island_removal_mode 0)
			)
			(polygon
				(pts
					(xy 488.83189 -34.309812) (xy 489.33989 -34.309812) (xy 489.33989 -33.928812) (xy 488.83189 -33.928812)
				)
			)
		)
		(zone
			(layer "B.Cu")
			(hatch none 0.5)
			(connect_pads
				(clearance 0)
			)
			(min_thickness 0.25)
			(keepout
				(tracks allowed)
				(vias not_allowed)
				(pads allowed)
				(copperpour not_allowed)
				(footprints allowed)
			)
			(placement
				(enabled no)
				(sheetname "")
			)
			(fill
				(thermal_gap 0.5)
				(thermal_bridge_width 0.5)
				(island_removal_mode 0)
			)
			(polygon
				(pts
					(xy 488.83189 -33.928812) (xy 489.33989 -33.928812) (xy 489.33989 -34.309812) (xy 488.83189 -34.309812)
				)
			)
		)
	)
)
